# T6G (Grand Teton) — schematic netlist excerpt (pin names and nets, part order shuffled) for the footprints in the layout excerpt that follows; sources: Cadence DE-HDL packaged netlist, KiCad conversion of 04192023_DAF0TMB3IC0_F0TG_MB_C_brd_V02_OCP.brd

PR148  Q_RES  20K 1% CHIP  pkg 0402LF  page 226 : A = PVDD18_S5_P1_FB ; B = PVDD18_S5_P1_FB_RC
C52  Q_CAP_DIFFBUS  DIFF BUS_0.22UF 6.3V 20% X6S  pkg C0201  page 67 : \1\ = P5E_CPU1_P3_TX_C_DN<13> ; \2\ = P5E_CPU1_P3_TX_DN<13>
R1291  Q_RES  10 1% CHIP  pkg 0402LF  page 357 : A = P12V_OCP_V3_2 ; B = VSENSE_P12V_INA230_7_INP

(kicad_pcb
	(version 20260206)
	(generator "pcbnew")
	(generator_version "10.0")
	(general
		(thickness 1.6)
		(legacy_teardrops no)
	)
	(paper "A4")
	(title_block
		(title "04192023_DAF0TMB3IC0_F0TG_MB_C_brd_V02_OCP.brd")
		(comment 1 "Grand Teton / footprints 295-297 of 8354")
	)
	(layers
		(0 "F.Cu" signal "TOP")
		(4 "In1.Cu" signal "GND")
		(6 "In2.Cu" signal "IN1")
		(8 "In3.Cu" signal "GND1")
		(10 "In4.Cu" signal "IN2")
		(12 "In5.Cu" signal "GND2")
		(14 "In6.Cu" signal "IN3")
		(16 "In7.Cu" signal "GND3")
		(18 "In8.Cu" signal "VCC")
		(20 "In9.Cu" signal "VCC1")
		(22 "In10.Cu" signal "GND4")
		(24 "In11.Cu" signal "IN4")
		(26 "In12.Cu" signal "GND5")
		(28 "In13.Cu" signal "IN5")
		(30 "In14.Cu" signal "GND6")
		(32 "In15.Cu" signal "IN6")
		(34 "In16.Cu" signal "GND7")
		(2 "B.Cu" signal "BOTTOM")
		(9 "F.Adhes" user "F.Adhesive")
		(11 "B.Adhes" user "B.Adhesive")
		(13 "F.Paste" user "Package Geometry/Pastemask Top")
		(15 "B.Paste" user "Package Geometry/Pastemask Bottom")
		(5 "F.SilkS" user "Ref Des/Silkscreen Top")
		(7 "B.SilkS" user "Ref Des/Silkscreen Bottom")
		(1 "F.Mask" user "Board Geometry/Soldermask Top")
		(3 "B.Mask" user "Board Geometry/Soldermask Bottom")
		(17 "Dwgs.User" user "User.Drawings")
		(19 "Cmts.User" user "User.Comments")
		(21 "Eco1.User" user "User.Eco1")
		(23 "Eco2.User" user "User.Eco2")
		(25 "Edge.Cuts" user "Board Geometry/Outline")
		(27 "Margin" user)
		(31 "F.CrtYd" user "Package Geometry/Place Bound Top")
		(29 "B.CrtYd" user "Package Geometry/Place Bound Bottom")
		(35 "F.Fab" user "Ref Des/Assembly Top")
		(33 "B.Fab" user "Ref Des/Assembly Bottom")
	)
	(footprint ""
		(layer "F.Cu")
		(at 136.531096 -370.57203 -90)
		(property "Reference" "C52"
			(at 0 0 270)
			(layer "F.SilkS")
			(hide yes)
			(effects
				(font
					(size 1.27 1.27)
				)
			)
		)
		(property "Value" ""
			(at 0 0 270)
			(layer "F.Fab")
			(effects
				(font
					(size 1.27 1.27)
				)
			)
		)
		(duplicate_pad_numbers_are_jumpers no)
		(fp_line
			(start -0.299974 0.150114)
			(end -0.299974 -0.150114)
			(stroke
				(width 0.1)
				(type default)
			)
			(layer "F.Fab")
		)
		(fp_line
			(start 0.299974 0.150114)
			(end -0.299974 0.150114)
			(stroke
				(width 0.1)
				(type default)
			)
			(layer "F.Fab")
		)
		(fp_line
			(start -0.299974 -0.150114)
			(end 0.299974 -0.150114)
			(stroke
				(width 0.1)
				(type default)
			)
			(layer "F.Fab")
		)
		(fp_line
			(start 0.299974 -0.150114)
			(end 0.299974 0.150114)
			(stroke
				(width 0.1)
				(type default)
			)
			(layer "F.Fab")
		)
		(pad "1" smd rect
			(at -0.2667 0 270)
			(size 0.3048 0.381)
			(layers "F.Cu" "F.Mask" "F.Paste")
			(net "P5E_CPU1_P3_TX_C_DN<13>")
		)
		(pad "2" smd rect
			(at 0.2667 0 270)
			(size 0.3048 0.381)
			(layers "F.Cu" "F.Mask" "F.Paste")
			(net "P5E_CPU1_P3_TX_DN<13>")
		)
	)
	(footprint ""
		(layer "F.Cu")
		(at 72.463914 -147.649692 180)
		(property "Reference" "PR148"
			(at 0 0 180)
			(layer "F.SilkS")
			(hide yes)
			(effects
				(font
					(size 1.27 1.27)
				)
			)
		)
		(property "Value" ""
			(at 0 0 180)
			(layer "F.Fab")
			(effects
				(font
					(size 1.27 1.27)
				)
			)
		)
		(duplicate_pad_numbers_are_jumpers no)
		(fp_line
			(start 0.7874 0.4064)
			(end -0.7874 0.4064)
			(stroke
				(width 0.1524)
				(type default)
			)
			(layer "F.SilkS")
		)
		(fp_line
			(start 0.7874 -0.4064)
			(end 0.7874 0.4064)
			(stroke
				(width 0.1524)
				(type default)
			)
			(layer "F.SilkS")
		)
		(fp_line
			(start -0.7874 0.4064)
			(end -0.7874 -0.4064)
			(stroke
				(width 0.1524)
				(type default)
			)
			(layer "F.SilkS")
		)
		(fp_line
			(start -0.7874 -0.4064)
			(end 0.7874 -0.4064)
			(stroke
				(width 0.1524)
				(type default)
			)
			(layer "F.SilkS")
		)
		(fp_line
			(start 0.67945 0.3048)
			(end 0.120396 0.3048)
			(stroke
				(width 0.1)
				(type default)
			)
			(layer "F.Fab")
		)
		(fp_line
			(start 0.67945 -0.3048)
			(end 0.67945 0.3048)
			(stroke
				(width 0.1)
				(type default)
			)
			(layer "F.Fab")
		)
		(fp_line
			(start 0.12065 -0.2794)
			(end 0.12065 -0.3048)
			(stroke
				(width 0.1)
				(type default)
			)
			(layer "F.Fab")
		)
		(fp_line
			(start 0.12065 -0.3048)
			(end 0.67945 -0.3048)
			(stroke
				(width 0.1)
				(type default)
			)
			(layer "F.Fab")
		)
		(fp_line
			(start 0.120396 0.3048)
			(end 0.120396 0.2794)
			(stroke
				(width 0.1)
				(type default)
			)
			(layer "F.Fab")
		)
		(fp_line
			(start 0.120396 0.2794)
			(end -0.12065 0.2794)
			(stroke
				(width 0.1)
				(type default)
			)
			(layer "F.Fab")
		)
		(fp_line
			(start -0.12065 0.3048)
			(end -0.67945 0.3048)
			(stroke
				(width 0.1)
				(type default)
			)
			(layer "F.Fab")
		)
		(fp_line
			(start -0.12065 0.2794)
			(end -0.12065 0.3048)
			(stroke
				(width 0.1)
				(type default)
			)
			(layer "F.Fab")
		)
		(fp_line
			(start -0.12065 -0.2794)
			(end 0.12065 -0.2794)
			(stroke
				(width 0.1)
				(type default)
			)
			(layer "F.Fab")
		)
		(fp_line
			(start -0.12065 -0.305054)
			(end -0.12065 -0.2794)
			(stroke
				(width 0.1)
				(type default)
			)
			(layer "F.Fab")
		)
		(fp_line
			(start -0.67945 0.3048)
			(end -0.67945 -0.305054)
			(stroke
				(width 0.1)
				(type default)
			)
			(layer "F.Fab")
		)
		(fp_line
			(start -0.67945 -0.305054)
			(end -0.12065 -0.305054)
			(stroke
				(width 0.1)
				(type default)
			)
			(layer "F.Fab")
		)
		(pad "1" smd circle
			(at -0.40005 0 180)
			(size 0 0)
			(layers "F.Cu" "F.Mask" "F.Paste")
			(net "PVDD18_S5_P1_FB")
		)
		(pad "2" smd circle
			(at 0.40005 0 180)
			(size 0 0)
			(layers "F.Cu" "F.Mask" "F.Paste")
			(net "PVDD18_S5_P1_FB_RC")
		)
	)
	(footprint ""
		(layer "F.Cu")
		(at 71.235824 -18.932144 180)
		(property "Reference" "R1291"
			(at 0 0 180)
			(layer "F.SilkS")
			(hide yes)
			(effects
				(font
					(size 1.27 1.27)
				)
			)
		)
		(property "Value" ""
			(at 0 0 180)
			(layer "F.Fab")
			(effects
				(font
					(size 1.27 1.27)
				)
			)
		)
		(duplicate_pad_numbers_are_jumpers no)
		(fp_line
			(start 0.7874 0.4064)
			(end -0.7874 0.4064)
			(stroke
				(width 0.1524)
				(type default)
			)
			(layer "F.SilkS")
		)
		(fp_line
			(start 0.7874 -0.4064)
			(end 0.7874 0.4064)
			(stroke
				(width 0.1524)
				(type default)
			)
			(layer "F.SilkS")
		)
		(fp_line
			(start -0.7874 0.4064)
			(end -0.7874 -0.4064)
			(stroke
				(width 0.1524)
				(type default)
			)
			(layer "F.SilkS")
		)
		(fp_line
			(start -0.7874 -0.4064)
			(end 0.7874 -0.4064)
			(stroke
				(width 0.1524)
				(type default)
			)
			(layer "F.SilkS")
		)
		(fp_line
			(start 0.67945 0.3048)
			(end 0.120396 0.3048)
			(stroke
				(width 0.1)
				(type default)
			)
			(layer "F.Fab")
		)
		(fp_line
			(start 0.67945 -0.3048)
			(end 0.67945 0.3048)
			(stroke
				(width 0.1)
				(type default)
			)
			(layer "F.Fab")
		)
		(fp_line
			(start 0.12065 -0.2794)
			(end 0.12065 -0.3048)
			(stroke
				(width 0.1)
				(type default)
			)
			(layer "F.Fab")
		)
		(fp_line
			(start 0.12065 -0.3048)
			(end 0.67945 -0.3048)
			(stroke
				(width 0.1)
				(type default)
			)
			(layer "F.Fab")
		)
		(fp_line
			(start 0.120396 0.3048)
			(end 0.120396 0.2794)
			(stroke
				(width 0.1)
				(type default)
			)
			(layer "F.Fab")
		)
		(fp_line
			(start 0.120396 0.2794)
			(end -0.12065 0.2794)
			(stroke
				(width 0.1)
				(type default)
			)
			(layer "F.Fab")
		)
		(fp_line
			(start -0.12065 0.3048)
			(end -0.67945 0.3048)
			(stroke
				(width 0.1)
				(type default)
			)
			(layer "F.Fab")
		)
		(fp_line
			(start -0.12065 0.2794)
			(end -0.12065 0.3048)
			(stroke
				(width 0.1)
				(type default)
			)
			(layer "F.Fab")
		)
		(fp_line
			(start -0.12065 -0.2794)
			(end 0.12065 -0.2794)
			(stroke
				(width 0.1)
				(type default)
			)
			(layer "F.Fab")
		)
		(fp_line
			(start -0.12065 -0.305054)
			(end -0.12065 -0.2794)
			(stroke
				(width 0.1)
				(type default)
			)
			(layer "F.Fab")
		)
		(fp_line
			(start -0.67945 0.3048)
			(end -0.67945 -0.305054)
			(stroke
				(width 0.1)
				(type default)
			)
			(layer "F.Fab")
		)
		(fp_line
			(start -0.67945 -0.305054)
			(end -0.12065 -0.305054)
			(stroke
				(width 0.1)
				(type default)
			)
			(layer "F.Fab")
		)
		(pad "1" smd circle
			(at -0.40005 0 180)
			(size 0 0)
			(layers "F.Cu" "F.Mask" "F.Paste")
			(net "P12V_OCP_V3_2")
		)
		(pad "2" smd circle
			(at 0.40005 0 180)
			(size 0 0)
			(layers "F.Cu" "F.Mask" "F.Paste")
			(net "VSENSE_P12V_INA230_7_INP")
		)
	)
)
